(kicad_pcb
	(version 20260206)
	(generator "pcbnew")
	(generator_version "10.0")
	(general
		(thickness 1.6)
		(legacy_teardrops no)
	)
	(paper "A4")
	(title_block
		(title "03242023_DA0F0TMBIJ0_F0T_Motherboard_J_brd_V01_OCP.brd")
		(comment 1 "Grand Teton / footprints 2517-2522 of 6105")
	)
	(layers
		(0 "F.Cu" signal "TOP")
		(4 "In1.Cu" signal "GND")
		(6 "In2.Cu" signal "IN1")
		(8 "In3.Cu" signal "GND1")
		(10 "In4.Cu" signal "IN2")
		(12 "In5.Cu" signal "GND2")
		(14 "In6.Cu" signal "IN3")
		(16 "In7.Cu" signal "GND3")
		(18 "In8.Cu" signal "VCC")
		(20 "In9.Cu" signal "VCC1")
		(22 "In10.Cu" signal "GND4")
		(24 "In11.Cu" signal "IN4")
		(26 "In12.Cu" signal "GND5")
		(28 "In13.Cu" signal "IN5")
		(30 "In14.Cu" signal "GND6")
		(32 "In15.Cu" signal "IN6")
		(34 "In16.Cu" signal "GND7")
		(2 "B.Cu" signal "BOTTOM")
		(9 "F.Adhes" user "F.Adhesive")
		(11 "B.Adhes" user "B.Adhesive")
		(13 "F.Paste" user "Package Geometry/Pastemask Top")
		(15 "B.Paste" user "Package Geometry/Pastemask Bottom")
		(5 "F.SilkS" user "Ref Des/Silkscreen Top")
		(7 "B.SilkS" user "Ref Des/Silkscreen Bottom")
		(1 "F.Mask" user "Board Geometry/Soldermask Top")
		(3 "B.Mask" user "Board Geometry/Soldermask Bottom")
		(17 "Dwgs.User" user "User.Drawings")
		(19 "Cmts.User" user "User.Comments")
		(21 "Eco1.User" user "User.Eco1")
		(23 "Eco2.User" user "User.Eco2")
		(25 "Edge.Cuts" user "Board Geometry/Outline")
		(27 "Margin" user)
		(31 "F.CrtYd" user "Package Geometry/Place Bound Top")
		(29 "B.CrtYd" user "Package Geometry/Place Bound Bottom")
		(35 "F.Fab" user "Ref Des/Assembly Top")
		(33 "B.Fab" user "Ref Des/Assembly Bottom")
	)
	(footprint ""
		(layer "F.Cu")
		(at 214.86241 -26.111454 90)
		(property "Reference" "OSC1"
			(at 1.289812 2.894076 0)
			(unlocked yes)
			(layer "F.SilkS")
			(effects
				(font
					(size 0.7874 0.5842)
					(thickness 0.1524)
				)
				(justify left)
			)
		)
		(property "Value" ""
			(at 0 0 90)
			(layer "F.Fab")
			(effects
				(font
					(size 1.27 1.27)
				)
			)
		)
		(duplicate_pad_numbers_are_jumpers no)
		(fp_line
			(start 1.546098 -1.94945)
			(end -1.546098 -1.94945)
			(stroke
				(width 0.1524)
				(type default)
			)
			(layer "F.SilkS")
		)
		(fp_line
			(start -1.546098 -1.94945)
			(end -1.546098 1.94945)
			(stroke
				(width 0.1524)
				(type default)
			)
			(layer "F.SilkS")
		)
		(fp_line
			(start 1.546098 1.94945)
			(end 1.546098 -1.94945)
			(stroke
				(width 0.1524)
				(type default)
			)
			(layer "F.SilkS")
		)
		(fp_line
			(start -1.546098 1.94945)
			(end 1.546098 1.94945)
			(stroke
				(width 0.1524)
				(type default)
			)
			(layer "F.SilkS")
		)
		(fp_poly
			(pts
				(xy -0.947674 -2.054098) (xy -1.430274 -3.374898) (xy -0.312674 -3.374898)
			)
			(stroke
				(width 0)
				(type default)
			)
			(fill yes)
			(layer "F.SilkS")
		)
		(fp_line
			(start 1.299972 -1.649984)
			(end 1.299972 1.649984)
			(stroke
				(width 0.1)
				(type default)
			)
			(layer "F.Fab")
		)
		(fp_line
			(start -1.299972 -1.649984)
			(end 1.299972 -1.649984)
			(stroke
				(width 0.1)
				(type default)
			)
			(layer "F.Fab")
		)
		(fp_line
			(start 1.299972 1.649984)
			(end -1.299972 1.649984)
			(stroke
				(width 0.1)
				(type default)
			)
			(layer "F.Fab")
		)
		(fp_line
			(start -1.299972 1.649984)
			(end -1.299972 -1.649984)
			(stroke
				(width 0.1)
				(type default)
			)
			(layer "F.Fab")
		)
		(fp_poly
			(pts
				(xy -1.768094 -1.059942) (xy -3.088894 -1.694942) (xy -3.088894 -0.577342)
			)
			(stroke
				(width 0)
				(type default)
			)
			(fill yes)
			(layer "F.Fab")
		)
		(pad "1" smd rect
			(at -0.8001 -1.059942 90)
			(size 1.2192 1.4986)
			(layers "F.Cu" "F.Mask" "F.Paste")
			(net "CLK_50M_EN")
		)
		(pad "2" smd rect
			(at -0.8001 1.059942 270)
			(size 1.2192 1.4986)
			(layers "F.Cu" "F.Mask" "F.Paste")
			(net "GND")
		)
		(pad "3" smd rect
			(at 0.8001 1.059942 90)
			(size 1.2192 1.4986)
			(layers "F.Cu" "F.Mask" "F.Paste")
			(net "CLK_50M_RMII")
		)
		(pad "4" smd rect
			(at 0.8001 -1.059942 90)
			(size 1.2192 1.4986)
			(layers "F.Cu" "F.Mask" "F.Paste")
			(net "P3V3_AUX")
		)
	)
	(footprint ""
		(layer "F.Cu")
		(at 237.401608 -402.689822)
		(property "Reference" "PC2225"
			(at 0 0 0)
			(layer "F.SilkS")
			(hide yes)
			(effects
				(font
					(size 1.27 1.27)
				)
			)
		)
		(property "Value" ""
			(at 0 0 0)
			(layer "F.Fab")
			(effects
				(font
					(size 1.27 1.27)
				)
			)
		)
		(duplicate_pad_numbers_are_jumpers no)
		(fp_line
			(start -0.7874 -0.4064)
			(end 0.7874 -0.4064)
			(stroke
				(width 0.1524)
				(type default)
			)
			(layer "F.SilkS")
		)
		(fp_line
			(start -0.7874 0.4064)
			(end -0.7874 -0.4064)
			(stroke
				(width 0.1524)
				(type default)
			)
			(layer "F.SilkS")
		)
		(fp_line
			(start 0.7874 -0.4064)
			(end 0.7874 0.4064)
			(stroke
				(width 0.1524)
				(type default)
			)
			(layer "F.SilkS")
		)
		(fp_line
			(start 0.7874 0.4064)
			(end -0.7874 0.4064)
			(stroke
				(width 0.1524)
				(type default)
			)
			(layer "F.SilkS")
		)
		(fp_line
			(start -0.67945 -0.305054)
			(end -0.12065 -0.305054)
			(stroke
				(width 0.1)
				(type default)
			)
			(layer "F.Fab")
		)
		(fp_line
			(start -0.67945 0.3048)
			(end -0.67945 -0.305054)
			(stroke
				(width 0.1)
				(type default)
			)
			(layer "F.Fab")
		)
		(fp_line
			(start -0.12065 -0.305054)
			(end -0.12065 -0.2794)
			(stroke
				(width 0.1)
				(type default)
			)
			(layer "F.Fab")
		)
		(fp_line
			(start -0.12065 -0.2794)
			(end 0.12065 -0.2794)
			(stroke
				(width 0.1)
				(type default)
			)
			(layer "F.Fab")
		)
		(fp_line
			(start -0.12065 0.2794)
			(end -0.12065 0.3048)
			(stroke
				(width 0.1)
				(type default)
			)
			(layer "F.Fab")
		)
		(fp_line
			(start -0.12065 0.3048)
			(end -0.67945 0.3048)
			(stroke
				(width 0.1)
				(type default)
			)
			(layer "F.Fab")
		)
		(fp_line
			(start 0.120396 0.2794)
			(end -0.12065 0.2794)
			(stroke
				(width 0.1)
				(type default)
			)
			(layer "F.Fab")
		)
		(fp_line
			(start 0.120396 0.3048)
			(end 0.120396 0.2794)
			(stroke
				(width 0.1)
				(type default)
			)
			(layer "F.Fab")
		)
		(fp_line
			(start 0.12065 -0.3048)
			(end 0.67945 -0.3048)
			(stroke
				(width 0.1)
				(type default)
			)
			(layer "F.Fab")
		)
		(fp_line
			(start 0.12065 -0.2794)
			(end 0.12065 -0.3048)
			(stroke
				(width 0.1)
				(type default)
			)
			(layer "F.Fab")
		)
		(fp_line
			(start 0.67945 -0.3048)
			(end 0.67945 0.3048)
			(stroke
				(width 0.1)
				(type default)
			)
			(layer "F.Fab")
		)
		(fp_line
			(start 0.67945 0.3048)
			(end 0.120396 0.3048)
			(stroke
				(width 0.1)
				(type default)
			)
			(layer "F.Fab")
		)
		(pad "1" smd circle
			(at -0.40005 0)
			(size 0 0)
			(layers "F.Cu" "F.Mask" "F.Paste")
			(net "HSC_ON")
		)
		(pad "2" smd circle
			(at 0.40005 0)
			(size 0 0)
			(layers "F.Cu" "F.Mask" "F.Paste")
			(net "AGND_HSC")
		)
	)
	(footprint ""
		(layer "F.Cu")
		(at 27.22118 -385.760468 90)
		(property "Reference" "R4537"
			(at 0 0 90)
			(layer "F.SilkS")
			(hide yes)
			(effects
				(font
					(size 1.27 1.27)
				)
			)
		)
		(property "Value" ""
			(at 0 0 90)
			(layer "F.Fab")
			(effects
				(font
					(size 1.27 1.27)
				)
			)
		)
		(duplicate_pad_numbers_are_jumpers no)
		(fp_line
			(start 0.7874 -0.4064)
			(end 0.7874 0.4064)
			(stroke
				(width 0.1524)
				(type default)
			)
			(layer "F.SilkS")
		)
		(fp_line
			(start -0.7874 -0.4064)
			(end 0.7874 -0.4064)
			(stroke
				(width 0.1524)
				(type default)
			)
			(layer "F.SilkS")
		)
		(fp_line
			(start 0.7874 0.4064)
			(end -0.7874 0.4064)
			(stroke
				(width 0.1524)
				(type default)
			)
			(layer "F.SilkS")
		)
		(fp_line
			(start -0.7874 0.4064)
			(end -0.7874 -0.4064)
			(stroke
				(width 0.1524)
				(type default)
			)
			(layer "F.SilkS")
		)
		(fp_line
			(start -0.12065 -0.305054)
			(end -0.12065 -0.2794)
			(stroke
				(width 0.1)
				(type default)
			)
			(layer "F.Fab")
		)
		(fp_line
			(start -0.67945 -0.305054)
			(end -0.12065 -0.305054)
			(stroke
				(width 0.1)
				(type default)
			)
			(layer "F.Fab")
		)
		(fp_line
			(start 0.67945 -0.3048)
			(end 0.67945 0.3048)
			(stroke
				(width 0.1)
				(type default)
			)
			(layer "F.Fab")
		)
		(fp_line
			(start 0.12065 -0.3048)
			(end 0.67945 -0.3048)
			(stroke
				(width 0.1)
				(type default)
			)
			(layer "F.Fab")
		)
		(fp_line
			(start 0.12065 -0.2794)
			(end 0.12065 -0.3048)
			(stroke
				(width 0.1)
				(type default)
			)
			(layer "F.Fab")
		)
		(fp_line
			(start -0.12065 -0.2794)
			(end 0.12065 -0.2794)
			(stroke
				(width 0.1)
				(type default)
			)
			(layer "F.Fab")
		)
		(fp_line
			(start 0.120396 0.2794)
			(end -0.12065 0.2794)
			(stroke
				(width 0.1)
				(type default)
			)
			(layer "F.Fab")
		)
		(fp_line
			(start -0.12065 0.2794)
			(end -0.12065 0.3048)
			(stroke
				(width 0.1)
				(type default)
			)
			(layer "F.Fab")
		)
		(fp_line
			(start 0.67945 0.3048)
			(end 0.120396 0.3048)
			(stroke
				(width 0.1)
				(type default)
			)
			(layer "F.Fab")
		)
		(fp_line
			(start 0.120396 0.3048)
			(end 0.120396 0.2794)
			(stroke
				(width 0.1)
				(type default)
			)
			(layer "F.Fab")
		)
		(fp_line
			(start -0.12065 0.3048)
			(end -0.67945 0.3048)
			(stroke
				(width 0.1)
				(type default)
			)
			(layer "F.Fab")
		)
		(fp_line
			(start -0.67945 0.3048)
			(end -0.67945 -0.305054)
			(stroke
				(width 0.1)
				(type default)
			)
			(layer "F.Fab")
		)
		(pad "1" smd circle
			(at -0.40005 0 90)
			(size 0 0)
			(layers "F.Cu" "F.Mask" "F.Paste")
			(net "FM_P2E_EN_N")
		)
		(pad "2" smd circle
			(at 0.40005 0 90)
			(size 0 0)
			(layers "F.Cu" "F.Mask" "F.Paste")
			(net "CLK_GEN2_GPU_FPGA_OE_OR_N")
		)
	)
	(footprint ""
		(layer "F.Cu")
		(at 371.545358 -92.962984 -90)
		(property "Reference" "R1347"
			(at 0 0 270)
			(layer "F.SilkS")
			(hide yes)
			(effects
				(font
					(size 1.27 1.27)
				)
			)
		)
		(property "Value" ""
			(at 0 0 270)
			(layer "F.Fab")
			(effects
				(font
					(size 1.27 1.27)
				)
			)
		)
		(duplicate_pad_numbers_are_jumpers no)
		(fp_line
			(start -0.7874 0.4064)
			(end -0.7874 -0.4064)
			(stroke
				(width 0.1524)
				(type default)
			)
			(layer "F.SilkS")
		)
		(fp_line
			(start 0.7874 0.4064)
			(end -0.7874 0.4064)
			(stroke
				(width 0.1524)
				(type default)
			)
			(layer "F.SilkS")
		)
		(fp_line
			(start -0.7874 -0.4064)
			(end 0.7874 -0.4064)
			(stroke
				(width 0.1524)
				(type default)
			)
			(layer "F.SilkS")
		)
		(fp_line
			(start 0.7874 -0.4064)
			(end 0.7874 0.4064)
			(stroke
				(width 0.1524)
				(type default)
			)
			(layer "F.SilkS")
		)
		(fp_line
			(start -0.67945 0.3048)
			(end -0.67945 -0.305054)
			(stroke
				(width 0.1)
				(type default)
			)
			(layer "F.Fab")
		)
		(fp_line
			(start -0.12065 0.3048)
			(end -0.67945 0.3048)
			(stroke
				(width 0.1)
				(type default)
			)
			(layer "F.Fab")
		)
		(fp_line
			(start 0.120396 0.3048)
			(end 0.120396 0.2794)
			(stroke
				(width 0.1)
				(type default)
			)
			(layer "F.Fab")
		)
		(fp_line
			(start 0.67945 0.3048)
			(end 0.120396 0.3048)
			(stroke
				(width 0.1)
				(type default)
			)
			(layer "F.Fab")
		)
		(fp_line
			(start -0.12065 0.2794)
			(end -0.12065 0.3048)
			(stroke
				(width 0.1)
				(type default)
			)
			(layer "F.Fab")
		)
		(fp_line
			(start 0.120396 0.2794)
			(end -0.12065 0.2794)
			(stroke
				(width 0.1)
				(type default)
			)
			(layer "F.Fab")
		)
		(fp_line
			(start -0.12065 -0.2794)
			(end 0.12065 -0.2794)
			(stroke
				(width 0.1)
				(type default)
			)
			(layer "F.Fab")
		)
		(fp_line
			(start 0.12065 -0.2794)
			(end 0.12065 -0.3048)
			(stroke
				(width 0.1)
				(type default)
			)
			(layer "F.Fab")
		)
		(fp_line
			(start 0.12065 -0.3048)
			(end 0.67945 -0.3048)
			(stroke
				(width 0.1)
				(type default)
			)
			(layer "F.Fab")
		)
		(fp_line
			(start 0.67945 -0.3048)
			(end 0.67945 0.3048)
			(stroke
				(width 0.1)
				(type default)
			)
			(layer "F.Fab")
		)
		(fp_line
			(start -0.67945 -0.305054)
			(end -0.12065 -0.305054)
			(stroke
				(width 0.1)
				(type default)
			)
			(layer "F.Fab")
		)
		(fp_line
			(start -0.12065 -0.305054)
			(end -0.12065 -0.2794)
			(stroke
				(width 0.1)
				(type default)
			)
			(layer "F.Fab")
		)
		(pad "1" smd circle
			(at -0.40005 0 270)
			(size 0 0)
			(layers "F.Cu" "F.Mask" "F.Paste")
			(net "PD_GTL2014_BMC_JTAG_VREF_1")
		)
		(pad "2" smd circle
			(at 0.40005 0 270)
			(size 0 0)
			(layers "F.Cu" "F.Mask" "F.Paste")
			(net "GND")
		)
	)
	(footprint ""
		(layer "F.Cu")
		(at 104.352852 -256.6543 -90)
		(property "Reference" "C446"
			(at 0 0 270)
			(layer "F.SilkS")
			(hide yes)
			(effects
				(font
					(size 1.27 1.27)
				)
			)
		)
		(property "Value" ""
			(at 0 0 270)
			(layer "F.Fab")
			(effects
				(font
					(size 1.27 1.27)
				)
			)
		)
		(duplicate_pad_numbers_are_jumpers no)
		(fp_line
			(start -0.7874 0.4064)
			(end -0.7874 -0.4064)
			(stroke
				(width 0.1524)
				(type default)
			)
			(layer "F.SilkS")
		)
		(fp_line
			(start 0.7874 0.4064)
			(end -0.7874 0.4064)
			(stroke
				(width 0.1524)
				(type default)
			)
			(layer "F.SilkS")
		)
		(fp_line
			(start -0.7874 -0.4064)
			(end 0.7874 -0.4064)
			(stroke
				(width 0.1524)
				(type default)
			)
			(layer "F.SilkS")
		)
		(fp_line
			(start 0.7874 -0.4064)
			(end 0.7874 0.4064)
			(stroke
				(width 0.1524)
				(type default)
			)
			(layer "F.SilkS")
		)
		(fp_line
			(start -0.67945 0.3048)
			(end -0.67945 -0.305054)
			(stroke
				(width 0.1)
				(type default)
			)
			(layer "F.Fab")
		)
		(fp_line
			(start -0.12065 0.3048)
			(end -0.67945 0.3048)
			(stroke
				(width 0.1)
				(type default)
			)
			(layer "F.Fab")
		)
		(fp_line
			(start 0.120396 0.3048)
			(end 0.120396 0.2794)
			(stroke
				(width 0.1)
				(type default)
			)
			(layer "F.Fab")
		)
		(fp_line
			(start 0.67945 0.3048)
			(end 0.120396 0.3048)
			(stroke
				(width 0.1)
				(type default)
			)
			(layer "F.Fab")
		)
		(fp_line
			(start -0.12065 0.2794)
			(end -0.12065 0.3048)
			(stroke
				(width 0.1)
				(type default)
			)
			(layer "F.Fab")
		)
		(fp_line
			(start 0.120396 0.2794)
			(end -0.12065 0.2794)
			(stroke
				(width 0.1)
				(type default)
			)
			(layer "F.Fab")
		)
		(fp_line
			(start -0.12065 -0.2794)
			(end 0.12065 -0.2794)
			(stroke
				(width 0.1)
				(type default)
			)
			(layer "F.Fab")
		)
		(fp_line
			(start 0.12065 -0.2794)
			(end 0.12065 -0.3048)
			(stroke
				(width 0.1)
				(type default)
			)
			(layer "F.Fab")
		)
		(fp_line
			(start 0.12065 -0.3048)
			(end 0.67945 -0.3048)
			(stroke
				(width 0.1)
				(type default)
			)
			(layer "F.Fab")
		)
		(fp_line
			(start 0.67945 -0.3048)
			(end 0.67945 0.3048)
			(stroke
				(width 0.1)
				(type default)
			)
			(layer "F.Fab")
		)
		(fp_line
			(start -0.67945 -0.305054)
			(end -0.12065 -0.305054)
			(stroke
				(width 0.1)
				(type default)
			)
			(layer "F.Fab")
		)
		(fp_line
			(start -0.12065 -0.305054)
			(end -0.12065 -0.2794)
			(stroke
				(width 0.1)
				(type default)
			)
			(layer "F.Fab")
		)
		(pad "1" smd circle
			(at -0.40005 0 270)
			(size 0 0)
			(layers "F.Cu" "F.Mask" "F.Paste")
			(net "PVCCFA_EHV_CPU1")
		)
		(pad "2" smd circle
			(at 0.40005 0 270)
			(size 0 0)
			(layers "F.Cu" "F.Mask" "F.Paste")
			(net "GND")
		)
	)
	(footprint ""
		(layer "F.Cu")
		(at 162.34283 -78.984348)
		(property "Reference" "R2210"
			(at 0 0 0)
			(layer "F.SilkS")
			(hide yes)
			(effects
				(font
					(size 1.27 1.27)
				)
			)
		)
		(property "Value" ""
			(at 0 0 0)
			(layer "F.Fab")
			(effects
				(font
					(size 1.27 1.27)
				)
			)
		)
		(duplicate_pad_numbers_are_jumpers no)
		(fp_line
			(start -0.7874 -0.4064)
			(end 0.7874 -0.4064)
			(stroke
				(width 0.1524)
				(type default)
			)
			(layer "F.SilkS")
		)
		(fp_line
			(start -0.7874 0.4064)
			(end -0.7874 -0.4064)
			(stroke
				(width 0.1524)
				(type default)
			)
			(layer "F.SilkS")
		)
		(fp_line
			(start 0.7874 -0.4064)
			(end 0.7874 0.4064)
			(stroke
				(width 0.1524)
				(type default)
			)
			(layer "F.SilkS")
		)
		(fp_line
			(start 0.7874 0.4064)
			(end -0.7874 0.4064)
			(stroke
				(width 0.1524)
				(type default)
			)
			(layer "F.SilkS")
		)
		(fp_line
			(start -0.67945 -0.305054)
			(end -0.12065 -0.305054)
			(stroke
				(width 0.1)
				(type default)
			)
			(layer "F.Fab")
		)
		(fp_line
			(start -0.67945 0.3048)
			(end -0.67945 -0.305054)
			(stroke
				(width 0.1)
				(type default)
			)
			(layer "F.Fab")
		)
		(fp_line
			(start -0.12065 -0.305054)
			(end -0.12065 -0.2794)
			(stroke
				(width 0.1)
				(type default)
			)
			(layer "F.Fab")
		)
		(fp_line
			(start -0.12065 -0.2794)
			(end 0.12065 -0.2794)
			(stroke
				(width 0.1)
				(type default)
			)
			(layer "F.Fab")
		)
		(fp_line
			(start -0.12065 0.2794)
			(end -0.12065 0.3048)
			(stroke
				(width 0.1)
				(type default)
			)
			(layer "F.Fab")
		)
		(fp_line
			(start -0.12065 0.3048)
			(end -0.67945 0.3048)
			(stroke
				(width 0.1)
				(type default)
			)
			(layer "F.Fab")
		)
		(fp_line
			(start 0.120396 0.2794)
			(end -0.12065 0.2794)
			(stroke
				(width 0.1)
				(type default)
			)
			(layer "F.Fab")
		)
		(fp_line
			(start 0.120396 0.3048)
			(end 0.120396 0.2794)
			(stroke
				(width 0.1)
				(type default)
			)
			(layer "F.Fab")
		)
		(fp_line
			(start 0.12065 -0.3048)
			(end 0.67945 -0.3048)
			(stroke
				(width 0.1)
				(type default)
			)
			(layer "F.Fab")
		)
		(fp_line
			(start 0.12065 -0.2794)
			(end 0.12065 -0.3048)
			(stroke
				(width 0.1)
				(type default)
			)
			(layer "F.Fab")
		)
		(fp_line
			(start 0.67945 -0.3048)
			(end 0.67945 0.3048)
			(stroke
				(width 0.1)
				(type default)
			)
			(layer "F.Fab")
		)
		(fp_line
			(start 0.67945 0.3048)
			(end 0.120396 0.3048)
			(stroke
				(width 0.1)
				(type default)
			)
			(layer "F.Fab")
		)
		(pad "1" smd circle
			(at -0.40005 0)
			(size 0 0)
			(layers "F.Cu" "F.Mask" "F.Paste")
			(net "SMB_S3M_CPU1_3V3AUX_SDA_R")
		)
		(pad "2" smd circle
			(at 0.40005 0)
			(size 0 0)
			(layers "F.Cu" "F.Mask" "F.Paste")
			(net "SMB_S3M_CPU1_3V3AUX_SDA")
		)
	)
)
